#ISCELL
  pure_quanta quanta_title_block_c *
  *
#ISCELL
  pure_quanta_power cad_note *
  *
#CELL
  pure_quanta genoa_sp5 *
  page37_i167
#ISCELL
  mstr_standard offpage *
  page37_i168
#ISCELL
  mstr_standard offpage *
  page37_i169
#ISCELL
  mstr_standard tap *
  page37_i170
#ISCELL
  mstr_standard tap *
  page37_i171
#ISCELL
  mstr_standard tap *
  page37_i172
#ISCELL
  mstr_standard tap *
  page37_i173
#ISCELL
  mstr_standard tap *
  page37_i174
#ISCELL
  mstr_standard tap *
  page37_i175
#ISCELL
  mstr_standard tap *
  page37_i176
#ISCELL
  mstr_standard tap *
  page37_i177
#ISCELL
  mstr_standard tap *
  page37_i178
#ISCELL
  mstr_standard tap *
  page37_i179
#ISCELL
  mstr_standard tap *
  page37_i180
#ISCELL
  mstr_standard tap *
  page37_i181
#ISCELL
  mstr_standard tap *
  page37_i182
#ISCELL
  mstr_standard tap *
  page37_i183
#ISCELL
  mstr_standard tap *
  page37_i184
#ISCELL
  mstr_standard tap *
  page37_i185
#ISCELL
  mstr_standard tap *
  page37_i186
#ISCELL
  mstr_standard tap *
  page37_i187
#ISCELL
  mstr_standard tap *
  page37_i188
#ISCELL
  mstr_standard tap *
  page37_i189
#ISCELL
  mstr_standard tap *
  page37_i190
#ISCELL
  mstr_standard tap *
  page37_i191
#ISCELL
  mstr_standard tap *
  page37_i192
#ISCELL
  mstr_standard tap *
  page37_i193
#ISCELL
  mstr_standard tap *
  page37_i194
#ISCELL
  mstr_standard tap *
  page37_i195
#ISCELL
  mstr_standard tap *
  page37_i196
#ISCELL
  mstr_standard tap *
  page37_i197
#ISCELL
  mstr_standard tap *
  page37_i198
#ISCELL
  mstr_standard tap *
  page37_i199
#ISCELL
  mstr_standard tap *
  page37_i200
#ISCELL
  mstr_standard tap *
  page37_i201
#ISCELL
  mstr_standard tap *
  page37_i202
#ISCELL
  mstr_standard tap *
  page37_i203
#ISCELL
  mstr_standard tap *
  page37_i204
#ISCELL
  mstr_standard tap *
  page37_i205
#ISCELL
  mstr_standard offpage *
  page37_i206
#ISCELL
  mstr_standard tap *
  page37_i207
#ISCELL
  mstr_standard tap *
  page37_i208
#ISCELL
  mstr_standard tap *
  page37_i209
#ISCELL
  mstr_standard tap *
  page37_i210
#ISCELL
  mstr_standard tap *
  page37_i211
#ISCELL
  mstr_standard tap *
  page37_i212
#ISCELL
  mstr_standard tap *
  page37_i213
#ISCELL
  mstr_standard tap *
  page37_i214
#ISCELL
  mstr_standard tap *
  page37_i215
#ISCELL
  mstr_standard tap *
  page37_i216
#ISCELL
  mstr_standard tap *
  page37_i217
#ISCELL
  mstr_standard tap *
  page37_i218
#ISCELL
  mstr_standard tap *
  page37_i219
#ISCELL
  mstr_standard tap *
  page37_i220
#ISCELL
  mstr_standard tap *
  page37_i221
#ISCELL
  mstr_standard tap *
  page37_i222
#ISCELL
  mstr_standard tap *
  page37_i223
#ISCELL
  mstr_standard tap *
  page37_i224
#ISCELL
  mstr_standard tap *
  page37_i225
#ISCELL
  mstr_standard tap *
  page37_i226
#ISCELL
  mstr_standard tap *
  page37_i227
#ISCELL
  mstr_standard tap *
  page37_i228
#ISCELL
  mstr_standard tap *
  page37_i229
#ISCELL
  mstr_standard tap *
  page37_i230
#ISCELL
  mstr_standard tap *
  page37_i231
#ISCELL
  mstr_standard tap *
  page37_i232
#ISCELL
  mstr_standard tap *
  page37_i233
#ISCELL
  mstr_standard tap *
  page37_i234
#ISCELL
  mstr_standard tap *
  page37_i235
#ISCELL
  mstr_standard tap *
  page37_i236
#ISCELL
  mstr_standard tap *
  page37_i237
#ISCELL
  mstr_standard tap *
  page37_i238
#ISCELL
  mstr_standard tap *
  page37_i239
#ISCELL
  mstr_standard tap *
  page37_i240
#ISCELL
  mstr_standard tap *
  page37_i241
#ISCELL
  mstr_standard tap *
  page37_i242
#ISCELL
  mstr_standard offpage *
  page37_i243
#ISCELL
  mstr_standard tap *
  page37_i244
#ISCELL
  mstr_standard tap *
  page37_i245
#ISCELL
  mstr_standard tap *
  page37_i246
#ISCELL
  mstr_standard tap *
  page37_i247
#ISCELL
  mstr_standard tap *
  page37_i248
#ISCELL
  mstr_standard tap *
  page37_i249
#ISCELL
  mstr_standard tap *
  page37_i250
#ISCELL
  mstr_standard tap *
  page37_i251
#ISCELL
  mstr_standard tap *
  page37_i252
#ISCELL
  mstr_standard tap *
  page37_i253
#ISCELL
  mstr_standard tap *
  page37_i254
#ISCELL
  mstr_standard tap *
  page37_i255
#ISCELL
  mstr_standard tap *
  page37_i256
#ISCELL
  mstr_standard tap *
  page37_i257
#ISCELL
  mstr_standard tap *
  page37_i258
#ISCELL
  mstr_standard tap *
  page37_i259
#ISCELL
  mstr_standard tap *
  page37_i260
#ISCELL
  mstr_standard tap *
  page37_i261
#ISCELL
  mstr_standard tap *
  page37_i262
#ISCELL
  mstr_standard tap *
  page37_i263
#ISCELL
  mstr_standard tap *
  page37_i264
#ISCELL
  mstr_standard tap *
  page37_i265
#ISCELL
  mstr_standard tap *
  page37_i266
#ISCELL
  mstr_standard tap *
  page37_i267
#ISCELL
  mstr_standard tap *
  page37_i268
#ISCELL
  mstr_standard tap *
  page37_i269
#ISCELL
  mstr_standard tap *
  page37_i270
#ISCELL
  mstr_standard tap *
  page37_i271
#ISCELL
  mstr_standard tap *
  page37_i272
#ISCELL
  mstr_standard tap *
  page37_i273
#ISCELL
  mstr_standard tap *
  page37_i274
#ISCELL
  mstr_standard tap *
  page37_i275
#ISCELL
  mstr_standard tap *
  page37_i276
#ISCELL
  mstr_standard tap *
  page37_i277
#ISCELL
  mstr_standard tap *
  page37_i278
#ISCELL
  mstr_standard tap *
  page37_i279
#ISCELL
  mstr_standard tap *
  page37_i280
#ISCELL
  mstr_standard tap *
  page37_i281
#ISCELL
  mstr_standard tap *
  page37_i282
#ISCELL
  mstr_standard tap *
  page37_i283
#ISCELL
  mstr_standard tap *
  page37_i284
#ISCELL
  mstr_standard tap *
  page37_i285
#ISCELL
  mstr_standard tap *
  page37_i286
#ISCELL
  mstr_standard tap *
  page37_i287
#ISCELL
  mstr_standard tap *
  page37_i288
#ISCELL
  mstr_standard tap *
  page37_i289
#ISCELL
  mstr_standard tap *
  page37_i290
#ISCELL
  standard offpage *
  page37_i291
#ISCELL
  standard offpage *
  page37_i292
#ISCELL
  standard offpage *
  page37_i293
#ISCELL
  standard offpage *
  page37_i294
#ISCELL
  mstr_standard tap *
  page37_i295
#ISCELL
  mstr_standard tap *
  page37_i296
#ISCELL
  mstr_standard tap *
  page37_i297
#ISCELL
  mstr_standard tap *
  page37_i298
#ISCELL
  mstr_standard tap *
  page37_i299
#ISCELL
  mstr_standard tap *
  page37_i300
#ISCELL
  mstr_standard tap *
  page37_i301
#ISCELL
  mstr_standard tap *
  page37_i302
#ISCELL
  mstr_standard tap *
  page37_i303
#ISCELL
  mstr_standard tap *
  page37_i304
#ISCELL
  mstr_standard tap *
  page37_i305
#ISCELL
  mstr_standard tap *
  page37_i306
#ISCELL
  mstr_standard tap *
  page37_i307
#ISCELL
  mstr_standard tap *
  page37_i308
#ISCELL
  mstr_standard tap *
  page37_i309
#ISCELL
  standard offpage *
  page37_i310
#ISCELL
  standard offpage *
  page37_i311
#ISCELL
  standard offpage *
  page37_i312
#ISCELL
  standard offpage *
  page37_i313
#ISCELL
  standard offpage *
  page37_i314
#ISCELL
  standard offpage *
  page37_i315
#ISCELL
  standard offpage *
  page37_i316
#ISCELL
  mstr_standard offpage *
  page37_i317
#ISCELL
  standard offpage *
  page37_i318
#ISCELL
  standard offpage *
  page37_i319
#ISCELL
  standard offpage *
  page37_i320
#ISCELL
  standard offpage *
  page37_i321
#CELL
  pure_quanta q_res *
  page37_i322
#ISCELL
  standard offpage *
  page37_i323
#ISCELL
  mstr_standard offpage *
  page37_i324
